FILE_TYPE = CONNECTIVITY;
{Allegro Design Entry HDL 17.4-2019 S026 (4007227) 1/17/2022}
"PAGE_NUMBER" = 399;
0"NC";
1"GND\g";
2"GND\g";
3"GND\g";
4"GND\g";
5"SMB_RT_CPU1_P0_ROM_R_SDA";
6"SMB_RT_CPU1_P0_ROM_SDA";
7"SMB_RT_CPU1_P0_ROM_R_SCL";
8"SMB_RT_CPU1_P0_ROM_SCL";
9"P1V8_CPU1_RT_1D\g";
10"U12_E2";
%"P1V0"
"1","(-4500,6000)","0","pure_quanta_power","I10";
;
HDL_POWER"P1V8_CPU1_RT_1D"
CDS_LIB"pure_quanta_power";
"A"9;
%"Q_CAP"
"1","(-4725,5700)","0","pure_quanta","I11";
;
LOCATION"C7501"
$SEC"1"
CDS_SEC"1"
MATERIAL"X7S"
TOLERANCE"10%"
PACK_TYPE"C0201"
VOLTAGE"10V"
VALUE"0.1UF"
CDS_LIB"pure_quanta"
PART_NUMBER"CH4102K6E00";
"B"
$PN"2"1;
"A"
$PN"1"9;
%"UNIVERSAL_GND"
"1","(-4725,5425)","0","pure_quanta_power","I12";
;
CDS_LIB"pure_quanta_power"
HDL_POWER"GND";
"A"1;
%"Q_RES"
"2","(-3350,4950)","0","pure_quanta","I13";
;
LOCATION"R6788"
$SEC"1"
CDS_SEC"1"
WATTAGE"1/20W"
TOLERANCE"1%"
VALUE"1K"
PACK_TYPE"0201LF"
MATERIAL"CHIP"
CDS_LIB"pure_quanta"
PART_NUMBER"CS21001FE07";
"A"
$PN"1"10;
"B"
$PN"2"2;
%"UNIVERSAL_GND"
"1","(-3350,4525)","0","pure_quanta_power","I14";
;
CDS_LIB"pure_quanta_power"
HDL_POWER"GND";
"A"2;
%"UNIVERSAL_GND"
"1","(-4500,5150)","7","pure_quanta_power","I15";
;
CDS_LIB"pure_quanta_power"
HDL_POWER"GND";
"A"3;
%"Q_RES"
"1","(-5450,5100)","0","pure_quanta","I3";
;
LOCATION"R672"
$SEC"1"
CDS_SEC"1"
MATERIAL"CHIP"
WATTAGE"1/20W"
PACK_TYPE"0201LF"
VALUE"33.2"
TOLERANCE"1%"
CDS_LIB"pure_quanta"
PART_NUMBER"CS03321FE09";
"B"
$PN"2"8;
"A"
$PN"1"7;
%"Q_RES"
"1","(-5450,5050)","0","pure_quanta","I4";
;
LOCATION"R673"
$SEC"1"
CDS_SEC"1"
MATERIAL"CHIP"
CDS_LIB"pure_quanta"
WATTAGE"1/20W"
PACK_TYPE"0201LF"
VALUE"33.2"
TOLERANCE"1%"
PART_NUMBER"CS03321FE09";
"B"
$PN"2"6;
"A"
$PN"1"5;
%"M24M02DRMN6TP"
"1","(-4025,5125)","0","pure_quanta","I5";
;
LOCATION"U12"
$SEC"1"
CDS_SEC"1"
PART_TYPE"SMLF"
MATERIAL"IC"
VALUE"M24M02-DRMN6TP"
NEEDS_NO_SIZE"TRUE"
CDS_LMAN_SYM_OUTLINE"-175,125,175,-125"
CDS_LIB"pure_quanta"
PART_NUMBER"AKE33Z00600";
"DU1"
$PN"1"0;
"DU2"
$PN"2"0;
"E2"
$PN"3"10;
"VSS"
$PN"4"4;
"SDA"
$PN"5"6;
"SCL"
$PN"6"8;
"WC_N \B"
$PN"7"3;
"VCC"
$PN"8"9;
%"UNIVERSAL_GND"
"1","(-3500,4875)","0","pure_quanta_power","I9";
;
CDS_LIB"pure_quanta_power"
HDL_POWER"GND";
"A"4;
END.
